(kicad_pcb
	(version 20260206)
	(generator "pcbnew")
	(generator_version "10.0")
	(general
		(thickness 1.6)
		(legacy_teardrops no)
	)
	(paper "A4")
	(title_block
		(title "panther-plus-userver — 13130-1b_20150205.brd")
		(comment 1 "Honey Badger (Wiwynn) / footprints 991-998 of 1509")
	)
	(layers
		(0 "F.Cu" signal "TOP")
		(4 "In1.Cu" signal "L2")
		(6 "In2.Cu" signal "L3")
		(8 "In3.Cu" signal "L4")
		(10 "In4.Cu" signal "L5")
		(12 "In5.Cu" signal "L6")
		(14 "In6.Cu" signal "L7")
		(16 "In7.Cu" signal "L8")
		(18 "In8.Cu" signal "L9")
		(20 "In9.Cu" signal "L10")
		(22 "In10.Cu" signal "L11")
		(2 "B.Cu" signal "BOTTOM")
		(9 "F.Adhes" user "F.Adhesive")
		(11 "B.Adhes" user "B.Adhesive")
		(13 "F.Paste" user "Package Geometry/Pastemask Top")
		(15 "B.Paste" user "Package Geometry/Pastemask Bottom")
		(5 "F.SilkS" user "Ref Des/Silkscreen Top")
		(7 "B.SilkS" user "Ref Des/Silkscreen Bottom")
		(1 "F.Mask" user "Board Geometry/Soldermask Top")
		(3 "B.Mask" user "Board Geometry/Soldermask Bottom")
		(17 "Dwgs.User" user "User.Drawings")
		(19 "Cmts.User" user "User.Comments")
		(21 "Eco1.User" user "User.Eco1")
		(23 "Eco2.User" user "User.Eco2")
		(25 "Edge.Cuts" user "Board Geometry/Outline")
		(27 "Margin" user)
		(31 "F.CrtYd" user "Package Geometry/Place Bound Top")
		(29 "B.CrtYd" user "Package Geometry/Place Bound Bottom")
		(35 "F.Fab" user "Ref Des/Assembly Top")
		(33 "B.Fab" user "Ref Des/Assembly Bottom")
	)
	(footprint ""
		(layer "B.Cu")
		(at 149.733 -45.466 90)
		(property "Reference" "C223"
			(at 0 0 90)
			(layer "B.SilkS")
			(hide yes)
			(effects
				(font
					(size 1.27 1.27)
				)
				(justify mirror)
			)
		)
		(property "Value" "SCD1U10V2KX-5GP"
			(at -1.1811 -2.7051 90)
			(unlocked yes)
			(layer "B.Fab")
			(hide yes)
			(effects
				(font
					(size 1.016 1.016)
					(thickness 0.1524)
				)
				(justify mirror)
			)
		)
		(property "Device Type" "C402H22"
			(at -1.1811 -4.2291 90)
			(unlocked yes)
			(layer "B.Fab")
			(hide yes)
			(effects
				(font
					(size 1.016 1.016)
					(thickness 0.1524)
				)
				(justify mirror)
			)
		)
		(duplicate_pad_numbers_are_jumpers no)
		(fp_rect
			(start 0.381 0.7366)
			(end -0.381 -0.7366)
			(stroke
				(width 0)
				(type default)
			)
			(fill no)
			(layer "B.CrtYd")
		)
		(fp_rect
			(start 0.381 0.7366)
			(end -0.381 -0.7366)
			(stroke
				(width 0)
				(type default)
			)
			(fill no)
			(layer "B.Fab")
		)
		(pad "1" smd custom
			(at 0 -0.4572 270)
			(size 0.1143 0.1143)
			(layers "B.Cu" "B.Mask" "B.Paste")
			(net "P1V2_FPGA_D")
			(options
				(clearance outline)
				(anchor circle)
			)
			(primitives
				(gr_poly
					(pts
						(arc
							(start -0.254 0.1778)
							(mid -0.239121 0.213721)
							(end -0.2032 0.2286)
						)
						(arc
							(start 0.2032 0.2286)
							(mid 0.239121 0.213721)
							(end 0.254 0.1778)
						)
						(arc
							(start 0.254 -0.1778)
							(mid 0.239121 -0.213721)
							(end 0.2032 -0.2286)
						)
						(arc
							(start -0.2032 -0.2286)
							(mid -0.239121 -0.213721)
							(end -0.254 -0.1778)
						)
					)
					(width 0)
					(fill yes)
				)
			)
		)
		(pad "2" smd custom
			(at 0 0.4572 270)
			(size 0.1143 0.1143)
			(layers "B.Cu" "B.Mask" "B.Paste")
			(net "GND")
			(options
				(clearance outline)
				(anchor circle)
			)
			(primitives
				(gr_poly
					(pts
						(arc
							(start -0.254 0.1778)
							(mid -0.239121 0.213721)
							(end -0.2032 0.2286)
						)
						(arc
							(start 0.2032 0.2286)
							(mid 0.239121 0.213721)
							(end 0.254 0.1778)
						)
						(arc
							(start 0.254 -0.1778)
							(mid 0.239121 -0.213721)
							(end 0.2032 -0.2286)
						)
						(arc
							(start -0.2032 -0.2286)
							(mid -0.239121 -0.213721)
							(end -0.254 -0.1778)
						)
					)
					(width 0)
					(fill yes)
				)
			)
		)
	)
	(footprint ""
		(layer "B.Cu")
		(at 184.4548 -26.3652)
		(property "Reference" "PR218"
			(at 0 0 0)
			(layer "B.SilkS")
			(hide yes)
			(effects
				(font
					(size 1.27 1.27)
				)
				(justify mirror)
			)
		)
		(property "Value" "10KR2F-2-GP"
			(at -1.7907 -1.1176 0)
			(unlocked yes)
			(layer "B.Fab")
			(hide yes)
			(effects
				(font
					(size 1.016 1.016)
					(thickness 0.1524)
				)
				(justify mirror)
			)
		)
		(property "Device Type" "R402H16"
			(at -1.7907 -2.6416 0)
			(unlocked yes)
			(layer "B.Fab")
			(hide yes)
			(effects
				(font
					(size 1.016 1.016)
					(thickness 0.1524)
				)
				(justify mirror)
			)
		)
		(duplicate_pad_numbers_are_jumpers no)
		(fp_rect
			(start 0.381 0.8382)
			(end -0.381 -0.8382)
			(stroke
				(width 0)
				(type default)
			)
			(fill no)
			(layer "B.CrtYd")
		)
		(fp_rect
			(start 0.381 0.8382)
			(end -0.381 -0.8382)
			(stroke
				(width 0)
				(type default)
			)
			(fill no)
			(layer "B.Fab")
		)
		(pad "1" smd custom
			(at 0 -0.4318 180)
			(size 0.127 0.127)
			(layers "B.Cu" "B.Mask" "B.Paste")
			(net "ISENSE_PVDDR_A_ISEN1")
			(options
				(clearance outline)
				(anchor circle)
			)
			(primitives
				(gr_poly
					(pts
						(arc
							(start -0.2032 0.2794)
							(mid -0.239121 0.264521)
							(end -0.254 0.2286)
						)
						(arc
							(start -0.254 -0.2286)
							(mid -0.239121 -0.264521)
							(end -0.2032 -0.2794)
						)
						(arc
							(start 0.2032 -0.2794)
							(mid 0.239121 -0.264521)
							(end 0.254 -0.2286)
						)
						(arc
							(start 0.254 0.2286)
							(mid 0.239121 0.264521)
							(end 0.2032 0.2794)
						)
					)
					(width 0)
					(fill yes)
				)
			)
		)
		(pad "2" smd custom
			(at 0 0.4318 180)
			(size 0.127 0.127)
			(layers "B.Cu" "B.Mask" "B.Paste")
			(net "VR_PVDDRA_R_IS")
			(options
				(clearance outline)
				(anchor circle)
			)
			(primitives
				(gr_poly
					(pts
						(arc
							(start -0.2032 0.2794)
							(mid -0.239121 0.264521)
							(end -0.254 0.2286)
						)
						(arc
							(start -0.254 -0.2286)
							(mid -0.239121 -0.264521)
							(end -0.2032 -0.2794)
						)
						(arc
							(start 0.2032 -0.2794)
							(mid 0.239121 -0.264521)
							(end 0.254 -0.2286)
						)
						(arc
							(start 0.254 0.2286)
							(mid 0.239121 0.264521)
							(end 0.2032 0.2794)
						)
					)
					(width 0)
					(fill yes)
				)
			)
		)
	)
	(footprint ""
		(layer "B.Cu")
		(at 197.7136 -58.5724 -90)
		(property "Reference" "PC177"
			(at 0 0 90)
			(layer "B.SilkS")
			(hide yes)
			(effects
				(font
					(size 1.27 1.27)
				)
				(justify mirror)
			)
		)
		(property "Value" "SC22U6D3V5MX-2GP"
			(at 0 -4.9022 270)
			(unlocked yes)
			(layer "B.Fab")
			(hide yes)
			(effects
				(font
					(size 1.016 1.016)
					(thickness 0.1524)
				)
				(justify mirror)
			)
		)
		(property "Device Type" "C805H58"
			(at 0 -6.8072 270)
			(unlocked yes)
			(layer "B.Fab")
			(hide yes)
			(effects
				(font
					(size 1.016 1.016)
					(thickness 0.1524)
				)
				(justify mirror)
			)
		)
		(duplicate_pad_numbers_are_jumpers no)
		(fp_line
			(start -0.6096 0)
			(end 0.6096 0)
			(stroke
				(width 0.3048)
				(type default)
			)
			(layer "B.SilkS")
		)
		(fp_poly
			(pts
				(xy 0.9017 1.4351) (xy -0.9017 1.4351) (xy -0.9017 -1.4351) (xy 0.9017 -1.4351)
			)
			(stroke
				(width 0)
				(type default)
			)
			(fill no)
			(layer "B.CrtYd")
		)
		(fp_poly
			(pts
				(xy -0.9017 1.4351) (xy -0.9017 -1.4351) (xy 0.9017 -1.4351) (xy 0.9017 1.4351)
			)
			(stroke
				(width 0)
				(type default)
			)
			(fill no)
			(layer "B.Fab")
		)
		(pad "1" smd rect
			(at 0 -0.8382 90)
			(size 1.5494 0.9398)
			(layers "B.Cu" "B.Mask" "B.Paste")
			(net "PV_VDDR")
		)
		(pad "2" smd rect
			(at 0 0.8382 90)
			(size 1.5494 0.9398)
			(layers "B.Cu" "B.Mask" "B.Paste")
			(net "GND")
		)
	)
	(footprint ""
		(layer "B.Cu")
		(at 15.875 -67.2592 90)
		(property "Reference" "C173"
			(at 0 0 90)
			(layer "B.SilkS")
			(hide yes)
			(effects
				(font
					(size 1.27 1.27)
				)
				(justify mirror)
			)
		)
		(property "Value" "SCD1U16V2KX-3GP"
			(at -1.8923 -1.2065 90)
			(unlocked yes)
			(layer "B.Fab")
			(hide yes)
			(effects
				(font
					(size 1.016 1.016)
					(thickness 0.1524)
				)
				(justify mirror)
			)
		)
		(property "Device Type" "C402H22"
			(at -1.8923 -2.7305 90)
			(unlocked yes)
			(layer "B.Fab")
			(hide yes)
			(effects
				(font
					(size 1.016 1.016)
					(thickness 0.1524)
				)
				(justify mirror)
			)
		)
		(duplicate_pad_numbers_are_jumpers no)
		(fp_rect
			(start 0.381 0.7366)
			(end -0.381 -0.7366)
			(stroke
				(width 0)
				(type default)
			)
			(fill no)
			(layer "B.CrtYd")
		)
		(fp_rect
			(start 0.381 0.7366)
			(end -0.381 -0.7366)
			(stroke
				(width 0)
				(type default)
			)
			(fill no)
			(layer "B.Fab")
		)
		(pad "1" smd custom
			(at 0 -0.4572 270)
			(size 0.1143 0.1143)
			(layers "B.Cu" "B.Mask" "B.Paste")
			(net "P3V3")
			(options
				(clearance outline)
				(anchor circle)
			)
			(primitives
				(gr_poly
					(pts
						(arc
							(start -0.254 0.1778)
							(mid -0.239121 0.213721)
							(end -0.2032 0.2286)
						)
						(arc
							(start 0.2032 0.2286)
							(mid 0.239121 0.213721)
							(end 0.254 0.1778)
						)
						(arc
							(start 0.254 -0.1778)
							(mid 0.239121 -0.213721)
							(end 0.2032 -0.2286)
						)
						(arc
							(start -0.2032 -0.2286)
							(mid -0.239121 -0.213721)
							(end -0.254 -0.1778)
						)
					)
					(width 0)
					(fill yes)
				)
			)
		)
		(pad "2" smd custom
			(at 0 0.4572 270)
			(size 0.1143 0.1143)
			(layers "B.Cu" "B.Mask" "B.Paste")
			(net "GND")
			(options
				(clearance outline)
				(anchor circle)
			)
			(primitives
				(gr_poly
					(pts
						(arc
							(start -0.254 0.1778)
							(mid -0.239121 0.213721)
							(end -0.2032 0.2286)
						)
						(arc
							(start 0.2032 0.2286)
							(mid 0.239121 0.213721)
							(end 0.254 0.1778)
						)
						(arc
							(start 0.254 -0.1778)
							(mid 0.239121 -0.213721)
							(end 0.2032 -0.2286)
						)
						(arc
							(start -0.2032 -0.2286)
							(mid -0.239121 -0.213721)
							(end -0.254 -0.1778)
						)
					)
					(width 0)
					(fill yes)
				)
			)
		)
	)
	(footprint ""
		(layer "B.Cu")
		(at 65.9638 -18.5674 90)
		(property "Reference" "PR183"
			(at 0 0 90)
			(layer "B.SilkS")
			(hide yes)
			(effects
				(font
					(size 1.27 1.27)
				)
				(justify mirror)
			)
		)
		(property "Value" "237KR2F-GP"
			(at -1.7907 -1.1176 90)
			(unlocked yes)
			(layer "B.Fab")
			(hide yes)
			(effects
				(font
					(size 1.016 1.016)
					(thickness 0.1524)
				)
				(justify mirror)
			)
		)
		(property "Device Type" "R402H16"
			(at -1.7907 -2.6416 90)
			(unlocked yes)
			(layer "B.Fab")
			(hide yes)
			(effects
				(font
					(size 1.016 1.016)
					(thickness 0.1524)
				)
				(justify mirror)
			)
		)
		(duplicate_pad_numbers_are_jumpers no)
		(fp_rect
			(start 0.381 0.8382)
			(end -0.381 -0.8382)
			(stroke
				(width 0)
				(type default)
			)
			(fill no)
			(layer "B.CrtYd")
		)
		(fp_rect
			(start 0.381 0.8382)
			(end -0.381 -0.8382)
			(stroke
				(width 0)
				(type default)
			)
			(fill no)
			(layer "B.Fab")
		)
		(pad "1" smd custom
			(at 0 -0.4318 270)
			(size 0.127 0.127)
			(layers "B.Cu" "B.Mask" "B.Paste")
			(net "VR_FB_R_P1V8_STBY")
			(options
				(clearance outline)
				(anchor circle)
			)
			(primitives
				(gr_poly
					(pts
						(arc
							(start -0.2032 0.2794)
							(mid -0.239121 0.264521)
							(end -0.254 0.2286)
						)
						(arc
							(start -0.254 -0.2286)
							(mid -0.239121 -0.264521)
							(end -0.2032 -0.2794)
						)
						(arc
							(start 0.2032 -0.2794)
							(mid 0.239121 -0.264521)
							(end 0.254 -0.2286)
						)
						(arc
							(start 0.254 0.2286)
							(mid 0.239121 0.264521)
							(end 0.2032 0.2794)
						)
					)
					(width 0)
					(fill yes)
				)
			)
		)
		(pad "2" smd custom
			(at 0 0.4318 270)
			(size 0.127 0.127)
			(layers "B.Cu" "B.Mask" "B.Paste")
			(net "VR_FB_P1V8_STBY")
			(options
				(clearance outline)
				(anchor circle)
			)
			(primitives
				(gr_poly
					(pts
						(arc
							(start -0.2032 0.2794)
							(mid -0.239121 0.264521)
							(end -0.254 0.2286)
						)
						(arc
							(start -0.254 -0.2286)
							(mid -0.239121 -0.264521)
							(end -0.2032 -0.2794)
						)
						(arc
							(start 0.2032 -0.2794)
							(mid 0.239121 -0.264521)
							(end 0.254 -0.2286)
						)
						(arc
							(start 0.254 0.2286)
							(mid 0.239121 0.264521)
							(end 0.2032 0.2794)
						)
					)
					(width 0)
					(fill yes)
				)
			)
		)
	)
	(footprint ""
		(layer "B.Cu")
		(at 103.251 -17.78 180)
		(property "Reference" "C336"
			(at 0 0 0)
			(layer "B.SilkS")
			(hide yes)
			(effects
				(font
					(size 1.27 1.27)
				)
				(justify mirror)
			)
		)
		(property "Value" "SCD1U10V2KX-5GP"
			(at -1.8923 -1.2065 180)
			(unlocked yes)
			(layer "B.Fab")
			(hide yes)
			(effects
				(font
					(size 1.016 1.016)
					(thickness 0.1524)
				)
				(justify mirror)
			)
		)
		(property "Device Type" "C402H22"
			(at -1.8923 -2.7305 180)
			(unlocked yes)
			(layer "B.Fab")
			(hide yes)
			(effects
				(font
					(size 1.016 1.016)
					(thickness 0.1524)
				)
				(justify mirror)
			)
		)
		(duplicate_pad_numbers_are_jumpers no)
		(fp_rect
			(start 0.381 0.7366)
			(end -0.381 -0.7366)
			(stroke
				(width 0)
				(type default)
			)
			(fill no)
			(layer "B.CrtYd")
		)
		(fp_rect
			(start 0.381 0.7366)
			(end -0.381 -0.7366)
			(stroke
				(width 0)
				(type default)
			)
			(fill no)
			(layer "B.Fab")
		)
		(pad "1" smd custom
			(at 0 -0.4572)
			(size 0.1143 0.1143)
			(layers "B.Cu" "B.Mask" "B.Paste")
			(net "P3V3")
			(options
				(clearance outline)
				(anchor circle)
			)
			(primitives
				(gr_poly
					(pts
						(arc
							(start -0.254 0.1778)
							(mid -0.239121 0.213721)
							(end -0.2032 0.2286)
						)
						(arc
							(start 0.2032 0.2286)
							(mid 0.239121 0.213721)
							(end 0.254 0.1778)
						)
						(arc
							(start 0.254 -0.1778)
							(mid 0.239121 -0.213721)
							(end 0.2032 -0.2286)
						)
						(arc
							(start -0.2032 -0.2286)
							(mid -0.239121 -0.213721)
							(end -0.254 -0.1778)
						)
					)
					(width 0)
					(fill yes)
				)
			)
		)
		(pad "2" smd custom
			(at 0 0.4572)
			(size 0.1143 0.1143)
			(layers "B.Cu" "B.Mask" "B.Paste")
			(net "GND")
			(options
				(clearance outline)
				(anchor circle)
			)
			(primitives
				(gr_poly
					(pts
						(arc
							(start -0.254 0.1778)
							(mid -0.239121 0.213721)
							(end -0.2032 0.2286)
						)
						(arc
							(start 0.2032 0.2286)
							(mid 0.239121 0.213721)
							(end 0.254 0.1778)
						)
						(arc
							(start 0.254 -0.1778)
							(mid 0.239121 -0.213721)
							(end 0.2032 -0.2286)
						)
						(arc
							(start -0.2032 -0.2286)
							(mid -0.239121 -0.213721)
							(end -0.254 -0.1778)
						)
					)
					(width 0)
					(fill yes)
				)
			)
		)
	)
	(footprint ""
		(layer "B.Cu")
		(at 154.6352 -12.828778 180)
		(property "Reference" "C363"
			(at 0 0 0)
			(layer "B.SilkS")
			(hide yes)
			(effects
				(font
					(size 1.27 1.27)
				)
				(justify mirror)
			)
		)
		(property "Value" "SC47U6D3V5MX-1-GP"
			(at 0 -4.9022 180)
			(unlocked yes)
			(layer "B.Fab")
			(hide yes)
			(effects
				(font
					(size 1.016 1.016)
					(thickness 0.1524)
				)
				(justify mirror)
			)
		)
		(property "Device Type" "C805H54"
			(at 0 -6.8072 180)
			(unlocked yes)
			(layer "B.Fab")
			(hide yes)
			(effects
				(font
					(size 1.016 1.016)
					(thickness 0.1524)
				)
				(justify mirror)
			)
		)
		(duplicate_pad_numbers_are_jumpers no)
		(fp_line
			(start -0.6096 0)
			(end 0.6096 0)
			(stroke
				(width 0.3048)
				(type default)
			)
			(layer "B.SilkS")
		)
		(fp_poly
			(pts
				(xy 0.9017 1.4351) (xy -0.9017 1.4351) (xy -0.9017 -1.4351) (xy 0.9017 -1.4351)
			)
			(stroke
				(width 0)
				(type default)
			)
			(fill no)
			(layer "B.CrtYd")
		)
		(fp_poly
			(pts
				(xy -0.9017 1.4351) (xy -0.9017 -1.4351) (xy 0.9017 -1.4351) (xy 0.9017 1.4351)
			)
			(stroke
				(width 0)
				(type default)
			)
			(fill no)
			(layer "B.Fab")
		)
		(pad "1" smd rect
			(at 0 -0.8382)
			(size 1.5494 0.9398)
			(layers "B.Cu" "B.Mask" "B.Paste")
			(net "PV_VDDR")
		)
		(pad "2" smd rect
			(at 0 0.8382)
			(size 1.5494 0.9398)
			(layers "B.Cu" "B.Mask" "B.Paste")
			(net "GND")
		)
	)
	(footprint ""
		(layer "B.Cu")
		(at 16.383 -48.133)
		(property "Reference" "C248"
			(at 0 0 0)
			(layer "B.SilkS")
			(hide yes)
			(effects
				(font
					(size 1.27 1.27)
				)
				(justify mirror)
			)
		)
		(property "Value" "SCD1U16V2KX-3GP"
			(at -1.8923 -1.2065 0)
			(unlocked yes)
			(layer "B.Fab")
			(hide yes)
			(effects
				(font
					(size 1.016 1.016)
					(thickness 0.1524)
				)
				(justify mirror)
			)
		)
		(property "Device Type" "C402H22"
			(at -1.8923 -2.7305 0)
			(unlocked yes)
			(layer "B.Fab")
			(hide yes)
			(effects
				(font
					(size 1.016 1.016)
					(thickness 0.1524)
				)
				(justify mirror)
			)
		)
		(duplicate_pad_numbers_are_jumpers no)
		(fp_rect
			(start 0.381 0.7366)
			(end -0.381 -0.7366)
			(stroke
				(width 0)
				(type default)
			)
			(fill no)
			(layer "B.CrtYd")
		)
		(fp_rect
			(start 0.381 0.7366)
			(end -0.381 -0.7366)
			(stroke
				(width 0)
				(type default)
			)
			(fill no)
			(layer "B.Fab")
		)
		(pad "1" smd custom
			(at 0 -0.4572 180)
			(size 0.1143 0.1143)
			(layers "B.Cu" "B.Mask" "B.Paste")
			(net "P3V3")
			(options
				(clearance outline)
				(anchor circle)
			)
			(primitives
				(gr_poly
					(pts
						(arc
							(start -0.254 0.1778)
							(mid -0.239121 0.213721)
							(end -0.2032 0.2286)
						)
						(arc
							(start 0.2032 0.2286)
							(mid 0.239121 0.213721)
							(end 0.254 0.1778)
						)
						(arc
							(start 0.254 -0.1778)
							(mid 0.239121 -0.213721)
							(end 0.2032 -0.2286)
						)
						(arc
							(start -0.2032 -0.2286)
							(mid -0.239121 -0.213721)
							(end -0.254 -0.1778)
						)
					)
					(width 0)
					(fill yes)
				)
			)
		)
		(pad "2" smd custom
			(at 0 0.4572 180)
			(size 0.1143 0.1143)
			(layers "B.Cu" "B.Mask" "B.Paste")
			(net "GND")
			(options
				(clearance outline)
				(anchor circle)
			)
			(primitives
				(gr_poly
					(pts
						(arc
							(start -0.254 0.1778)
							(mid -0.239121 0.213721)
							(end -0.2032 0.2286)
						)
						(arc
							(start 0.2032 0.2286)
							(mid 0.239121 0.213721)
							(end 0.254 0.1778)
						)
						(arc
							(start 0.254 -0.1778)
							(mid 0.239121 -0.213721)
							(end 0.2032 -0.2286)
						)
						(arc
							(start -0.2032 -0.2286)
							(mid -0.239121 -0.213721)
							(end -0.254 -0.1778)
						)
					)
					(width 0)
					(fill yes)
				)
			)
		)
	)
)
